(kicad_pcb
	(version 20260206)
	(generator "pcbnew")
	(generator_version "10.0")
	(general
		(thickness 1.6)
		(legacy_teardrops no)
	)
	(paper "A4")
	(title_block
		(title "Bryce Canyon_SCC_16316-1_OCP.brd")
		(comment 1 "Bryce Canyon / footprints 422-428 of 1561")
	)
	(layers
		(0 "F.Cu" signal "TOP")
		(4 "In1.Cu" signal "L2GND")
		(6 "In2.Cu" signal "L3")
		(8 "In3.Cu" signal "L4VCC")
		(10 "In4.Cu" signal "L5VCC")
		(12 "In5.Cu" signal "L6")
		(14 "In6.Cu" signal "L7GND")
		(2 "B.Cu" signal "BOTTOM")
		(9 "F.Adhes" user "F.Adhesive")
		(11 "B.Adhes" user "B.Adhesive")
		(13 "F.Paste" user "Package Geometry/Pastemask Top")
		(15 "B.Paste" user "Package Geometry/Pastemask Bottom")
		(5 "F.SilkS" user "Ref Des/Silkscreen Top")
		(7 "B.SilkS" user "Ref Des/Silkscreen Bottom")
		(1 "F.Mask" user "Board Geometry/Soldermask Top")
		(3 "B.Mask" user "Board Geometry/Soldermask Bottom")
		(17 "Dwgs.User" user "User.Drawings")
		(19 "Cmts.User" user "User.Comments")
		(21 "Eco1.User" user "User.Eco1")
		(23 "Eco2.User" user "User.Eco2")
		(25 "Edge.Cuts" user "Board Geometry/Outline")
		(27 "Margin" user)
		(31 "F.CrtYd" user "Package Geometry/Place Bound Top")
		(29 "B.CrtYd" user "Package Geometry/Place Bound Bottom")
		(35 "F.Fab" user "Ref Des/Assembly Top")
		(33 "B.Fab" user "Ref Des/Assembly Bottom")
	)
	(footprint ""
		(layer "F.Cu")
		(at 191.85382 -50.0888 -90)
		(property "Reference" "R396"
			(at 0 0 270)
			(layer "F.SilkS")
			(hide yes)
			(effects
				(font
					(size 1.27 1.27)
				)
			)
		)
		(property "Value" "10KR2F-2-GP"
			(at 0.064008 -3.993896 270)
			(unlocked yes)
			(layer "F.Fab")
			(hide yes)
			(effects
				(font
					(size 1.016 1.016)
					(thickness 0.1524)
				)
			)
		)
		(property "Device Type" "R402H16"
			(at 0.064008 -5.517896 270)
			(unlocked yes)
			(layer "F.Fab")
			(hide yes)
			(effects
				(font
					(size 1.016 1.016)
					(thickness 0.1524)
				)
			)
		)
		(duplicate_pad_numbers_are_jumpers no)
		(fp_line
			(start -0.508 -0.9398)
			(end -0.508 0.9398)
			(stroke
				(width 0.1524)
				(type default)
			)
			(layer "F.SilkS")
		)
		(fp_line
			(start 0.508 -0.9398)
			(end -0.508 -0.9398)
			(stroke
				(width 0.1524)
				(type default)
			)
			(layer "F.SilkS")
		)
		(fp_rect
			(start -0.508 0.9398)
			(end 0.508 -0.9398)
			(stroke
				(width 0)
				(type default)
			)
			(fill no)
			(layer "F.CrtYd")
		)
		(fp_rect
			(start -0.508 0.9398)
			(end 0.508 -0.9398)
			(stroke
				(width 0)
				(type default)
			)
			(fill no)
			(layer "F.Fab")
		)
		(pad "1" smd custom
			(at 0 -0.4445 270)
			(size 0.1397 0.1397)
			(layers "F.Cu" "F.Mask" "F.Paste")
			(net "P1V8_C")
			(options
				(clearance outline)
				(anchor circle)
			)
			(primitives
				(gr_poly
					(pts
						(arc
							(start -0.1778 -0.2794)
							(mid -0.249642 -0.249642)
							(end -0.2794 -0.1778)
						)
						(arc
							(start -0.2794 0.1778)
							(mid -0.249642 0.249642)
							(end -0.1778 0.2794)
						)
						(arc
							(start 0.1778 0.2794)
							(mid 0.249642 0.249642)
							(end 0.2794 0.1778)
						)
						(arc
							(start 0.2794 -0.1778)
							(mid 0.249642 -0.249642)
							(end 0.1778 -0.2794)
						)
					)
					(width 0)
					(fill yes)
				)
			)
		)
		(pad "2" smd custom
			(at 0 0.4445 270)
			(size 0.1397 0.1397)
			(layers "F.Cu" "F.Mask" "F.Paste")
			(net "XM_ADDR_11")
			(options
				(clearance outline)
				(anchor circle)
			)
			(primitives
				(gr_poly
					(pts
						(arc
							(start -0.1778 -0.2794)
							(mid -0.249642 -0.249642)
							(end -0.2794 -0.1778)
						)
						(arc
							(start -0.2794 0.1778)
							(mid -0.249642 0.249642)
							(end -0.1778 0.2794)
						)
						(arc
							(start 0.1778 0.2794)
							(mid 0.249642 0.249642)
							(end 0.2794 0.1778)
						)
						(arc
							(start 0.2794 -0.1778)
							(mid 0.249642 -0.249642)
							(end 0.1778 -0.2794)
						)
					)
					(width 0)
					(fill yes)
				)
			)
		)
	)
	(footprint ""
		(layer "F.Cu")
		(at 184.65038 -107.67822 -90)
		(property "Reference" "R8"
			(at 0 0 270)
			(layer "F.SilkS")
			(hide yes)
			(effects
				(font
					(size 1.27 1.27)
				)
			)
		)
		(property "Value" "4K53R2F-1-GP"
			(at 0.064008 -3.993896 270)
			(unlocked yes)
			(layer "F.Fab")
			(hide yes)
			(effects
				(font
					(size 1.016 1.016)
					(thickness 0.1524)
				)
			)
		)
		(property "Device Type" "R402H16"
			(at 0.064008 -5.517896 270)
			(unlocked yes)
			(layer "F.Fab")
			(hide yes)
			(effects
				(font
					(size 1.016 1.016)
					(thickness 0.1524)
				)
			)
		)
		(duplicate_pad_numbers_are_jumpers no)
		(fp_line
			(start -0.508 -0.9398)
			(end -0.508 0.9398)
			(stroke
				(width 0.1524)
				(type default)
			)
			(layer "F.SilkS")
		)
		(fp_line
			(start 0.508 -0.9398)
			(end -0.508 -0.9398)
			(stroke
				(width 0.1524)
				(type default)
			)
			(layer "F.SilkS")
		)
		(fp_rect
			(start -0.508 0.9398)
			(end 0.508 -0.9398)
			(stroke
				(width 0)
				(type default)
			)
			(fill no)
			(layer "F.CrtYd")
		)
		(fp_rect
			(start -0.508 0.9398)
			(end 0.508 -0.9398)
			(stroke
				(width 0)
				(type default)
			)
			(fill no)
			(layer "F.Fab")
		)
		(pad "1" smd custom
			(at 0 -0.4445 270)
			(size 0.1397 0.1397)
			(layers "F.Cu" "F.Mask" "F.Paste")
			(net "P0V9_G_PG")
			(options
				(clearance outline)
				(anchor circle)
			)
			(primitives
				(gr_poly
					(pts
						(arc
							(start -0.1778 -0.2794)
							(mid -0.249642 -0.249642)
							(end -0.2794 -0.1778)
						)
						(arc
							(start -0.2794 0.1778)
							(mid -0.249642 0.249642)
							(end -0.1778 0.2794)
						)
						(arc
							(start 0.1778 0.2794)
							(mid 0.249642 0.249642)
							(end 0.2794 0.1778)
						)
						(arc
							(start 0.2794 -0.1778)
							(mid 0.249642 -0.249642)
							(end 0.1778 -0.2794)
						)
					)
					(width 0)
					(fill yes)
				)
			)
		)
		(pad "2" smd custom
			(at 0 0.4445 270)
			(size 0.1397 0.1397)
			(layers "F.Cu" "F.Mask" "F.Paste")
			(net "P3V3")
			(options
				(clearance outline)
				(anchor circle)
			)
			(primitives
				(gr_poly
					(pts
						(arc
							(start -0.1778 -0.2794)
							(mid -0.249642 -0.249642)
							(end -0.2794 -0.1778)
						)
						(arc
							(start -0.2794 0.1778)
							(mid -0.249642 0.249642)
							(end -0.1778 0.2794)
						)
						(arc
							(start 0.1778 0.2794)
							(mid 0.249642 0.249642)
							(end 0.2794 0.1778)
						)
						(arc
							(start 0.2794 -0.1778)
							(mid 0.249642 -0.249642)
							(end 0.1778 -0.2794)
						)
					)
					(width 0)
					(fill yes)
				)
			)
		)
	)
	(footprint ""
		(layer "F.Cu")
		(at 12.6238 -100.6856)
		(property "Reference" "C733"
			(at 0 0 0)
			(layer "F.SilkS")
			(hide yes)
			(effects
				(font
					(size 1.27 1.27)
				)
			)
		)
		(property "Value" "SCD1U16V2KX-3GP"
			(at 1.1811 -2.7051 0)
			(unlocked yes)
			(layer "F.Fab")
			(hide yes)
			(effects
				(font
					(size 1.016 1.016)
					(thickness 0.1524)
				)
			)
		)
		(property "Device Type" "C402H22"
			(at 1.1811 -4.2291 0)
			(unlocked yes)
			(layer "F.Fab")
			(hide yes)
			(effects
				(font
					(size 1.016 1.016)
					(thickness 0.1524)
				)
			)
		)
		(duplicate_pad_numbers_are_jumpers no)
		(fp_rect
			(start -0.4318 0.9525)
			(end 0.4318 -0.9525)
			(stroke
				(width 0)
				(type default)
			)
			(fill no)
			(layer "F.CrtYd")
		)
		(fp_rect
			(start -0.4318 0.9525)
			(end 0.4318 -0.9525)
			(stroke
				(width 0)
				(type default)
			)
			(fill no)
			(layer "F.Fab")
		)
		(pad "1" smd custom
			(at 0 -0.4445)
			(size 0.1524 0.1524)
			(layers "F.Cu" "F.Mask" "F.Paste")
			(net "P3V3")
			(options
				(clearance outline)
				(anchor circle)
			)
			(primitives
				(gr_poly
					(pts
						(arc
							(start 0.3048 -0.2032)
							(mid 0.275042 -0.275042)
							(end 0.2032 -0.3048)
						)
						(arc
							(start -0.2032 -0.3048)
							(mid -0.275042 -0.275042)
							(end -0.3048 -0.2032)
						)
						(arc
							(start -0.3048 0.2032)
							(mid -0.275042 0.275042)
							(end -0.2032 0.3048)
						)
						(arc
							(start 0.2032 0.3048)
							(mid 0.275042 0.275042)
							(end 0.3048 0.2032)
						)
					)
					(width 0)
					(fill yes)
				)
			)
		)
		(pad "2" smd custom
			(at 0 0.4445)
			(size 0.1524 0.1524)
			(layers "F.Cu" "F.Mask" "F.Paste")
			(net "GND")
			(options
				(clearance outline)
				(anchor circle)
			)
			(primitives
				(gr_poly
					(pts
						(arc
							(start 0.3048 -0.2032)
							(mid 0.275042 -0.275042)
							(end 0.2032 -0.3048)
						)
						(arc
							(start -0.2032 -0.3048)
							(mid -0.275042 -0.275042)
							(end -0.3048 -0.2032)
						)
						(arc
							(start -0.3048 0.2032)
							(mid -0.275042 0.275042)
							(end -0.2032 0.3048)
						)
						(arc
							(start 0.2032 0.3048)
							(mid 0.275042 0.275042)
							(end 0.3048 0.2032)
						)
					)
					(width 0)
					(fill yes)
				)
			)
		)
	)
	(footprint ""
		(layer "F.Cu")
		(at 155.74518 -85.775292 -90)
		(property "Reference" "U25"
			(at 0 0 270)
			(layer "F.SilkS")
			(hide yes)
			(effects
				(font
					(size 1.27 1.27)
				)
			)
		)
		(property "Value" "ADS1015IDGSR-GP"
			(at 0 -11.1252 270)
			(unlocked yes)
			(layer "F.Fab")
			(hide yes)
			(effects
				(font
					(size 1.016 1.016)
					(thickness 0.1524)
				)
			)
		)
		(property "Device Type" "MSOP10H44"
			(at 0 -12.6492 270)
			(unlocked yes)
			(layer "F.Fab")
			(hide yes)
			(effects
				(font
					(size 1.016 1.016)
					(thickness 0.1524)
				)
			)
		)
		(duplicate_pad_numbers_are_jumpers no)
		(fp_line
			(start -2.0066 1.016)
			(end -2.0066 -1.016)
			(stroke
				(width 0.1524)
				(type default)
			)
			(layer "F.SilkS")
		)
		(fp_line
			(start -1.8288 1.016)
			(end -1.8288 3.048)
			(stroke
				(width 0.508)
				(type default)
			)
			(layer "F.SilkS")
		)
		(fp_line
			(start 1.143 1.016)
			(end -2.0066 1.016)
			(stroke
				(width 0.1524)
				(type default)
			)
			(layer "F.SilkS")
		)
		(fp_line
			(start -1.5748 0)
			(end -1.9558 0.381)
			(stroke
				(width 0.1524)
				(type default)
			)
			(layer "F.SilkS")
		)
		(fp_line
			(start -1.5748 0)
			(end -1.9558 -0.381)
			(stroke
				(width 0.1524)
				(type default)
			)
			(layer "F.SilkS")
		)
		(fp_line
			(start -2.0066 -1.016)
			(end 1.143 -1.016)
			(stroke
				(width 0.1524)
				(type default)
			)
			(layer "F.SilkS")
		)
		(fp_line
			(start 1.143 -1.016)
			(end 1.143 1.016)
			(stroke
				(width 0.1524)
				(type default)
			)
			(layer "F.SilkS")
		)
		(fp_poly
			(pts
				(xy -2.0828 3.3401) (xy 2.0828 3.3401) (xy 2.0828 -3.3401) (xy -2.0828 -3.3401)
			)
			(stroke
				(width 0)
				(type default)
			)
			(fill no)
			(layer "F.CrtYd")
		)
		(fp_poly
			(pts
				(xy -2.0828 3.3401) (xy 2.0828 3.3401) (xy 2.0828 -3.3401) (xy -2.0828 -3.3401)
			)
			(stroke
				(width 0)
				(type default)
			)
			(fill no)
			(layer "F.Fab")
		)
		(pad "1" smd rect
			(at -0.99949 2.0701 270)
			(size 0.3048 1.524)
			(layers "F.Cu" "F.Mask" "F.Paste")
			(net "VOL_SEN1_ADDR")
		)
		(pad "2" smd rect
			(at -0.50038 2.0701 270)
			(size 0.3048 1.524)
			(layers "F.Cu" "F.Mask" "F.Paste")
			(net "VOL_SEN1_ALERT")
		)
		(pad "3" smd rect
			(at 0 2.0701 270)
			(size 0.3048 1.524)
			(layers "F.Cu" "F.Mask" "F.Paste")
			(net "GND")
		)
		(pad "4" smd rect
			(at 0.50038 2.0701 270)
			(size 0.3048 1.524)
			(layers "F.Cu" "F.Mask" "F.Paste")
			(net "P3V3_SENSE")
		)
		(pad "5" smd rect
			(at 0.99949 2.0701 270)
			(size 0.3048 1.524)
			(layers "F.Cu" "F.Mask" "F.Paste")
			(net "P1V8_E_SENSE")
		)
		(pad "6" smd rect
			(at 0.99949 -2.0701 270)
			(size 0.3048 1.524)
			(layers "F.Cu" "F.Mask" "F.Paste")
			(net "P1V5_E_SENSE")
		)
		(pad "7" smd rect
			(at 0.50038 -2.0701 270)
			(size 0.3048 1.524)
			(layers "F.Cu" "F.Mask" "F.Paste")
			(net "P0V9_SENSE")
		)
		(pad "8" smd rect
			(at 0 -2.0701 270)
			(size 0.3048 1.524)
			(layers "F.Cu" "F.Mask" "F.Paste")
			(net "P3V3")
		)
		(pad "9" smd rect
			(at -0.50038 -2.0701 270)
			(size 0.3048 1.524)
			(layers "F.Cu" "F.Mask" "F.Paste")
			(net "VOL_SEN1_SDA")
		)
		(pad "10" smd rect
			(at -0.99949 -2.0701 270)
			(size 0.3048 1.524)
			(layers "F.Cu" "F.Mask" "F.Paste")
			(net "VOL_SEN1_SCL")
		)
	)
	(footprint ""
		(layer "F.Cu")
		(at 149.02688 -120.56872 180)
		(property "Reference" "R25"
			(at 0 0 180)
			(layer "F.SilkS")
			(hide yes)
			(effects
				(font
					(size 1.27 1.27)
				)
			)
		)
		(property "Value" "0R2J-2-GP"
			(at 0.064008 -3.993896 180)
			(unlocked yes)
			(layer "F.Fab")
			(hide yes)
			(effects
				(font
					(size 1.016 1.016)
					(thickness 0.1524)
				)
			)
		)
		(property "Device Type" "R402H16"
			(at 0.064008 -5.517896 180)
			(unlocked yes)
			(layer "F.Fab")
			(hide yes)
			(effects
				(font
					(size 1.016 1.016)
					(thickness 0.1524)
				)
			)
		)
		(duplicate_pad_numbers_are_jumpers no)
		(fp_line
			(start 0.508 -0.9398)
			(end -0.508 -0.9398)
			(stroke
				(width 0.1524)
				(type default)
			)
			(layer "F.SilkS")
		)
		(fp_line
			(start -0.508 -0.9398)
			(end -0.508 0.9398)
			(stroke
				(width 0.1524)
				(type default)
			)
			(layer "F.SilkS")
		)
		(fp_rect
			(start -0.508 0.9398)
			(end 0.508 -0.9398)
			(stroke
				(width 0)
				(type default)
			)
			(fill no)
			(layer "F.CrtYd")
		)
		(fp_rect
			(start -0.508 0.9398)
			(end 0.508 -0.9398)
			(stroke
				(width 0)
				(type default)
			)
			(fill no)
			(layer "F.Fab")
		)
		(pad "1" smd custom
			(at 0 -0.4445 180)
			(size 0.1397 0.1397)
			(layers "F.Cu" "F.Mask" "F.Paste")
			(net "P1V5_E_EN")
			(options
				(clearance outline)
				(anchor circle)
			)
			(primitives
				(gr_poly
					(pts
						(arc
							(start -0.1778 -0.2794)
							(mid -0.249642 -0.249642)
							(end -0.2794 -0.1778)
						)
						(arc
							(start -0.2794 0.1778)
							(mid -0.249642 0.249642)
							(end -0.1778 0.2794)
						)
						(arc
							(start 0.1778 0.2794)
							(mid 0.249642 0.249642)
							(end 0.2794 0.1778)
						)
						(arc
							(start 0.2794 -0.1778)
							(mid 0.249642 -0.249642)
							(end 0.1778 -0.2794)
						)
					)
					(width 0)
					(fill yes)
				)
			)
		)
		(pad "2" smd custom
			(at 0 0.4445 180)
			(size 0.1397 0.1397)
			(layers "F.Cu" "F.Mask" "F.Paste")
			(net "P1V8_E_PG")
			(options
				(clearance outline)
				(anchor circle)
			)
			(primitives
				(gr_poly
					(pts
						(arc
							(start -0.1778 -0.2794)
							(mid -0.249642 -0.249642)
							(end -0.2794 -0.1778)
						)
						(arc
							(start -0.2794 0.1778)
							(mid -0.249642 0.249642)
							(end -0.1778 0.2794)
						)
						(arc
							(start 0.1778 0.2794)
							(mid 0.249642 0.249642)
							(end 0.2794 0.1778)
						)
						(arc
							(start 0.2794 -0.1778)
							(mid 0.249642 -0.249642)
							(end 0.1778 -0.2794)
						)
					)
					(width 0)
					(fill yes)
				)
			)
		)
	)
	(footprint ""
		(layer "F.Cu")
		(at 169.507662 -58.072528)
		(property "Reference" "R267"
			(at 0 0 0)
			(layer "F.SilkS")
			(hide yes)
			(effects
				(font
					(size 1.27 1.27)
				)
			)
		)
		(property "Value" "4K7R2F-GP"
			(at 0.064008 -3.993896 0)
			(unlocked yes)
			(layer "F.Fab")
			(hide yes)
			(effects
				(font
					(size 1.016 1.016)
					(thickness 0.1524)
				)
			)
		)
		(property "Device Type" "R402H16"
			(at 0.064008 -5.517896 0)
			(unlocked yes)
			(layer "F.Fab")
			(hide yes)
			(effects
				(font
					(size 1.016 1.016)
					(thickness 0.1524)
				)
			)
		)
		(duplicate_pad_numbers_are_jumpers no)
		(fp_line
			(start -0.508 -0.9398)
			(end -0.508 0.9398)
			(stroke
				(width 0.1524)
				(type default)
			)
			(layer "F.SilkS")
		)
		(fp_line
			(start 0.508 -0.9398)
			(end -0.508 -0.9398)
			(stroke
				(width 0.1524)
				(type default)
			)
			(layer "F.SilkS")
		)
		(fp_rect
			(start -0.508 0.9398)
			(end 0.508 -0.9398)
			(stroke
				(width 0)
				(type default)
			)
			(fill no)
			(layer "F.CrtYd")
		)
		(fp_rect
			(start -0.508 0.9398)
			(end 0.508 -0.9398)
			(stroke
				(width 0)
				(type default)
			)
			(fill no)
			(layer "F.Fab")
		)
		(pad "1" smd custom
			(at 0 -0.4445)
			(size 0.1397 0.1397)
			(layers "F.Cu" "F.Mask" "F.Paste")
			(net "P1V8_C")
			(options
				(clearance outline)
				(anchor circle)
			)
			(primitives
				(gr_poly
					(pts
						(arc
							(start -0.1778 -0.2794)
							(mid -0.249642 -0.249642)
							(end -0.2794 -0.1778)
						)
						(arc
							(start -0.2794 0.1778)
							(mid -0.249642 0.249642)
							(end -0.1778 0.2794)
						)
						(arc
							(start 0.1778 0.2794)
							(mid 0.249642 0.249642)
							(end 0.2794 0.1778)
						)
						(arc
							(start 0.2794 -0.1778)
							(mid 0.249642 -0.249642)
							(end 0.1778 -0.2794)
						)
					)
					(width 0)
					(fill yes)
				)
			)
		)
		(pad "2" smd custom
			(at 0 0.4445)
			(size 0.1397 0.1397)
			(layers "F.Cu" "F.Mask" "F.Paste")
			(net "ICE0_TCK")
			(options
				(clearance outline)
				(anchor circle)
			)
			(primitives
				(gr_poly
					(pts
						(arc
							(start -0.1778 -0.2794)
							(mid -0.249642 -0.249642)
							(end -0.2794 -0.1778)
						)
						(arc
							(start -0.2794 0.1778)
							(mid -0.249642 0.249642)
							(end -0.1778 0.2794)
						)
						(arc
							(start 0.1778 0.2794)
							(mid 0.249642 0.249642)
							(end 0.2794 0.1778)
						)
						(arc
							(start 0.2794 -0.1778)
							(mid 0.249642 -0.249642)
							(end 0.1778 -0.2794)
						)
					)
					(width 0)
					(fill yes)
				)
			)
		)
	)
	(footprint ""
		(layer "F.Cu")
		(at 41.0972 -29.8958 -90)
		(property "Reference" "R91"
			(at 0 0 270)
			(layer "F.SilkS")
			(hide yes)
			(effects
				(font
					(size 1.27 1.27)
				)
			)
		)
		(property "Value" "200KR2F-L-GP"
			(at 0.064008 -3.993896 270)
			(unlocked yes)
			(layer "F.Fab")
			(hide yes)
			(effects
				(font
					(size 1.016 1.016)
					(thickness 0.1524)
				)
			)
		)
		(property "Device Type" "R402H16"
			(at 0.064008 -5.517896 270)
			(unlocked yes)
			(layer "F.Fab")
			(hide yes)
			(effects
				(font
					(size 1.016 1.016)
					(thickness 0.1524)
				)
			)
		)
		(duplicate_pad_numbers_are_jumpers no)
		(fp_line
			(start -0.508 -0.9398)
			(end -0.508 0.9398)
			(stroke
				(width 0.1524)
				(type default)
			)
			(layer "F.SilkS")
		)
		(fp_line
			(start 0.508 -0.9398)
			(end -0.508 -0.9398)
			(stroke
				(width 0.1524)
				(type default)
			)
			(layer "F.SilkS")
		)
		(fp_rect
			(start -0.508 0.9398)
			(end 0.508 -0.9398)
			(stroke
				(width 0)
				(type default)
			)
			(fill no)
			(layer "F.CrtYd")
		)
		(fp_rect
			(start -0.508 0.9398)
			(end 0.508 -0.9398)
			(stroke
				(width 0)
				(type default)
			)
			(fill no)
			(layer "F.Fab")
		)
		(pad "1" smd custom
			(at 0 -0.4445 270)
			(size 0.1397 0.1397)
			(layers "F.Cu" "F.Mask" "F.Paste")
			(net "P0V9_U8_PG")
			(options
				(clearance outline)
				(anchor circle)
			)
			(primitives
				(gr_poly
					(pts
						(arc
							(start -0.1778 -0.2794)
							(mid -0.249642 -0.249642)
							(end -0.2794 -0.1778)
						)
						(arc
							(start -0.2794 0.1778)
							(mid -0.249642 0.249642)
							(end -0.1778 0.2794)
						)
						(arc
							(start 0.1778 0.2794)
							(mid 0.249642 0.249642)
							(end 0.2794 0.1778)
						)
						(arc
							(start 0.2794 -0.1778)
							(mid 0.249642 -0.249642)
							(end 0.1778 -0.2794)
						)
					)
					(width 0)
					(fill yes)
				)
			)
		)
		(pad "2" smd custom
			(at 0 0.4445 270)
			(size 0.1397 0.1397)
			(layers "F.Cu" "F.Mask" "F.Paste")
			(net "P0V9_MODE")
			(options
				(clearance outline)
				(anchor circle)
			)
			(primitives
				(gr_poly
					(pts
						(arc
							(start -0.1778 -0.2794)
							(mid -0.249642 -0.249642)
							(end -0.2794 -0.1778)
						)
						(arc
							(start -0.2794 0.1778)
							(mid -0.249642 0.249642)
							(end -0.1778 0.2794)
						)
						(arc
							(start 0.1778 0.2794)
							(mid 0.249642 0.249642)
							(end 0.2794 0.1778)
						)
						(arc
							(start 0.2794 -0.1778)
							(mid 0.249642 -0.249642)
							(end 0.1778 -0.2794)
						)
					)
					(width 0)
					(fill yes)
				)
			)
		)
	)
)
